# S9S_MB_2U (Grand Teton) — schematic netlist excerpt (pin names and nets, part order shuffled) for the footprints in the layout excerpt that follows; sources: Cadence DE-HDL packaged netlist, KiCad conversion of 03242023_DA0F0TMBIJ0_F0T_Motherboard_J_brd_V01_OCP.brd

C2036  Q_CAP  8.2PF 50V 0.1P NP0  pkg C0402  page 208 : A = XTAL_CLK_GEN1_25M_X1_R ; B = GND
PC2232  Q_CAP  0.047UF 25V 10% X7R  pkg C0402  page 242 : A = P12V_SCM_SS ; B = GND

(kicad_pcb
	(version 20260206)
	(generator "pcbnew")
	(generator_version "10.0")
	(general
		(thickness 1.6)
		(legacy_teardrops no)
	)
	(paper "A4")
	(title_block
		(title "03242023_DA0F0TMBIJ0_F0T_Motherboard_J_brd_V01_OCP.brd")
		(comment 1 "Grand Teton / footprints 426-427 of 6105")
	)
	(layers
		(0 "F.Cu" signal "TOP")
		(4 "In1.Cu" signal "GND")
		(6 "In2.Cu" signal "IN1")
		(8 "In3.Cu" signal "GND1")
		(10 "In4.Cu" signal "IN2")
		(12 "In5.Cu" signal "GND2")
		(14 "In6.Cu" signal "IN3")
		(16 "In7.Cu" signal "GND3")
		(18 "In8.Cu" signal "VCC")
		(20 "In9.Cu" signal "VCC1")
		(22 "In10.Cu" signal "GND4")
		(24 "In11.Cu" signal "IN4")
		(26 "In12.Cu" signal "GND5")
		(28 "In13.Cu" signal "IN5")
		(30 "In14.Cu" signal "GND6")
		(32 "In15.Cu" signal "IN6")
		(34 "In16.Cu" signal "GND7")
		(2 "B.Cu" signal "BOTTOM")
		(9 "F.Adhes" user "F.Adhesive")
		(11 "B.Adhes" user "B.Adhesive")
		(13 "F.Paste" user "Package Geometry/Pastemask Top")
		(15 "B.Paste" user "Package Geometry/Pastemask Bottom")
		(5 "F.SilkS" user "Ref Des/Silkscreen Top")
		(7 "B.SilkS" user "Ref Des/Silkscreen Bottom")
		(1 "F.Mask" user "Board Geometry/Soldermask Top")
		(3 "B.Mask" user "Board Geometry/Soldermask Bottom")
		(17 "Dwgs.User" user "User.Drawings")
		(19 "Cmts.User" user "User.Comments")
		(21 "Eco1.User" user "User.Eco1")
		(23 "Eco2.User" user "User.Eco2")
		(25 "Edge.Cuts" user "Board Geometry/Outline")
		(27 "Margin" user)
		(31 "F.CrtYd" user "Package Geometry/Place Bound Top")
		(29 "B.CrtYd" user "Package Geometry/Place Bound Bottom")
		(35 "F.Fab" user "Ref Des/Assembly Top")
		(33 "B.Fab" user "Ref Des/Assembly Bottom")
	)
	(footprint ""
		(layer "F.Cu")
		(at 248.740676 -90.65514)
		(property "Reference" "C2036"
			(at 0 0 0)
			(layer "F.SilkS")
			(hide yes)
			(effects
				(font
					(size 1.27 1.27)
				)
			)
		)
		(property "Value" ""
			(at 0 0 0)
			(layer "F.Fab")
			(effects
				(font
					(size 1.27 1.27)
				)
			)
		)
		(duplicate_pad_numbers_are_jumpers no)
		(fp_line
			(start -0.7874 -0.4064)
			(end 0.7874 -0.4064)
			(stroke
				(width 0.1524)
				(type default)
			)
			(layer "F.SilkS")
		)
		(fp_line
			(start -0.7874 0.4064)
			(end -0.7874 -0.4064)
			(stroke
				(width 0.1524)
				(type default)
			)
			(layer "F.SilkS")
		)
		(fp_line
			(start 0.7874 -0.4064)
			(end 0.7874 0.4064)
			(stroke
				(width 0.1524)
				(type default)
			)
			(layer "F.SilkS")
		)
		(fp_line
			(start 0.7874 0.4064)
			(end -0.7874 0.4064)
			(stroke
				(width 0.1524)
				(type default)
			)
			(layer "F.SilkS")
		)
		(fp_line
			(start -0.67945 -0.305054)
			(end -0.12065 -0.305054)
			(stroke
				(width 0.1)
				(type default)
			)
			(layer "F.Fab")
		)
		(fp_line
			(start -0.67945 0.3048)
			(end -0.67945 -0.305054)
			(stroke
				(width 0.1)
				(type default)
			)
			(layer "F.Fab")
		)
		(fp_line
			(start -0.12065 -0.305054)
			(end -0.12065 -0.2794)
			(stroke
				(width 0.1)
				(type default)
			)
			(layer "F.Fab")
		)
		(fp_line
			(start -0.12065 -0.2794)
			(end 0.12065 -0.2794)
			(stroke
				(width 0.1)
				(type default)
			)
			(layer "F.Fab")
		)
		(fp_line
			(start -0.12065 0.2794)
			(end -0.12065 0.3048)
			(stroke
				(width 0.1)
				(type default)
			)
			(layer "F.Fab")
		)
		(fp_line
			(start -0.12065 0.3048)
			(end -0.67945 0.3048)
			(stroke
				(width 0.1)
				(type default)
			)
			(layer "F.Fab")
		)
		(fp_line
			(start 0.120396 0.2794)
			(end -0.12065 0.2794)
			(stroke
				(width 0.1)
				(type default)
			)
			(layer "F.Fab")
		)
		(fp_line
			(start 0.120396 0.3048)
			(end 0.120396 0.2794)
			(stroke
				(width 0.1)
				(type default)
			)
			(layer "F.Fab")
		)
		(fp_line
			(start 0.12065 -0.3048)
			(end 0.67945 -0.3048)
			(stroke
				(width 0.1)
				(type default)
			)
			(layer "F.Fab")
		)
		(fp_line
			(start 0.12065 -0.2794)
			(end 0.12065 -0.3048)
			(stroke
				(width 0.1)
				(type default)
			)
			(layer "F.Fab")
		)
		(fp_line
			(start 0.67945 -0.3048)
			(end 0.67945 0.3048)
			(stroke
				(width 0.1)
				(type default)
			)
			(layer "F.Fab")
		)
		(fp_line
			(start 0.67945 0.3048)
			(end 0.120396 0.3048)
			(stroke
				(width 0.1)
				(type default)
			)
			(layer "F.Fab")
		)
		(pad "1" smd circle
			(at -0.40005 0)
			(size 0 0)
			(layers "F.Cu" "F.Mask" "F.Paste")
			(net "XTAL_CLK_GEN1_25M_X1_R")
		)
		(pad "2" smd circle
			(at 0.40005 0)
			(size 0 0)
			(layers "F.Cu" "F.Mask" "F.Paste")
			(net "GND")
		)
	)
	(footprint ""
		(layer "F.Cu")
		(at 176.391062 -32.935672 90)
		(property "Reference" "PC2232"
			(at 0 0 90)
			(layer "F.SilkS")
			(hide yes)
			(effects
				(font
					(size 1.27 1.27)
				)
			)
		)
		(property "Value" ""
			(at 0 0 90)
			(layer "F.Fab")
			(effects
				(font
					(size 1.27 1.27)
				)
			)
		)
		(duplicate_pad_numbers_are_jumpers no)
		(fp_line
			(start 0.7874 -0.4064)
			(end 0.7874 0.4064)
			(stroke
				(width 0.1524)
				(type default)
			)
			(layer "F.SilkS")
		)
		(fp_line
			(start -0.7874 -0.4064)
			(end 0.7874 -0.4064)
			(stroke
				(width 0.1524)
				(type default)
			)
			(layer "F.SilkS")
		)
		(fp_line
			(start 0.7874 0.4064)
			(end -0.7874 0.4064)
			(stroke
				(width 0.1524)
				(type default)
			)
			(layer "F.SilkS")
		)
		(fp_line
			(start -0.7874 0.4064)
			(end -0.7874 -0.4064)
			(stroke
				(width 0.1524)
				(type default)
			)
			(layer "F.SilkS")
		)
		(fp_line
			(start -0.12065 -0.305054)
			(end -0.12065 -0.2794)
			(stroke
				(width 0.1)
				(type default)
			)
			(layer "F.Fab")
		)
		(fp_line
			(start -0.67945 -0.305054)
			(end -0.12065 -0.305054)
			(stroke
				(width 0.1)
				(type default)
			)
			(layer "F.Fab")
		)
		(fp_line
			(start 0.67945 -0.3048)
			(end 0.67945 0.3048)
			(stroke
				(width 0.1)
				(type default)
			)
			(layer "F.Fab")
		)
		(fp_line
			(start 0.12065 -0.3048)
			(end 0.67945 -0.3048)
			(stroke
				(width 0.1)
				(type default)
			)
			(layer "F.Fab")
		)
		(fp_line
			(start 0.12065 -0.2794)
			(end 0.12065 -0.3048)
			(stroke
				(width 0.1)
				(type default)
			)
			(layer "F.Fab")
		)
		(fp_line
			(start -0.12065 -0.2794)
			(end 0.12065 -0.2794)
			(stroke
				(width 0.1)
				(type default)
			)
			(layer "F.Fab")
		)
		(fp_line
			(start 0.120396 0.2794)
			(end -0.12065 0.2794)
			(stroke
				(width 0.1)
				(type default)
			)
			(layer "F.Fab")
		)
		(fp_line
			(start -0.12065 0.2794)
			(end -0.12065 0.3048)
			(stroke
				(width 0.1)
				(type default)
			)
			(layer "F.Fab")
		)
		(fp_line
			(start 0.67945 0.3048)
			(end 0.120396 0.3048)
			(stroke
				(width 0.1)
				(type default)
			)
			(layer "F.Fab")
		)
		(fp_line
			(start 0.120396 0.3048)
			(end 0.120396 0.2794)
			(stroke
				(width 0.1)
				(type default)
			)
			(layer "F.Fab")
		)
		(fp_line
			(start -0.12065 0.3048)
			(end -0.67945 0.3048)
			(stroke
				(width 0.1)
				(type default)
			)
			(layer "F.Fab")
		)
		(fp_line
			(start -0.67945 0.3048)
			(end -0.67945 -0.305054)
			(stroke
				(width 0.1)
				(type default)
			)
			(layer "F.Fab")
		)
		(pad "1" smd circle
			(at -0.40005 0 90)
			(size 0 0)
			(layers "F.Cu" "F.Mask" "F.Paste")
			(net "P12V_SCM_SS")
		)
		(pad "2" smd circle
			(at 0.40005 0 90)
			(size 0 0)
			(layers "F.Cu" "F.Mask" "F.Paste")
			(net "GND")
		)
	)
)
